# BASEBOARD_FAB2 (Tioga Pass) — schematic netlist excerpt (pin names and nets, part order shuffled) for the footprints in the layout excerpt that follows; sources: Cadence DE-HDL packaged netlist, KiCad conversion of Wiwynn_Tioga_Pass_MB.brd

R7W16  RES  0.0 5% CHIP  pkg 0402  page 120 : A = IRQ_DIMM_SAVE_LVT3_R_N ; B = IRQ_DIMM_SAVE_LVT3_N
C7G5  CAP  0.22UF 16V 10% X7R  pkg 0402  page 105 : A = P3E_CPU0_PE2_SS_TXP<15> ; B = P3E_CPU0_PE2_SS_C_TXP<15>
R4D38  RES  10.0K 1% EMPTY  pkg 0402  page 102 : A = P3V3_DB1200 ; B = FM_DB1200_SMB_SA1

(kicad_pcb
	(version 20260206)
	(generator "pcbnew")
	(generator_version "10.0")
	(general
		(thickness 1.6)
		(legacy_teardrops no)
	)
	(paper "A4")
	(title_block
		(title "Wiwynn_Tioga_Pass_MB.brd")
		(comment 1 "Tioga Pass / footprints 1872-1874 of 4770")
	)
	(layers
		(0 "F.Cu" signal "TOP")
		(4 "In1.Cu" signal "L2GND")
		(6 "In2.Cu" signal "L3")
		(8 "In3.Cu" signal "L4GND")
		(10 "In4.Cu" signal "L5")
		(12 "In5.Cu" signal "L6GND")
		(14 "In6.Cu" signal "L7VCC")
		(16 "In7.Cu" signal "L8VCC")
		(18 "In8.Cu" signal "L9GND")
		(20 "In9.Cu" signal "L10")
		(22 "In10.Cu" signal "L11GND")
		(24 "In11.Cu" signal "L12")
		(26 "In12.Cu" signal "L13GND")
		(2 "B.Cu" signal "BOTTOM")
		(9 "F.Adhes" user "F.Adhesive")
		(11 "B.Adhes" user "B.Adhesive")
		(13 "F.Paste" user "Package Geometry/Pastemask Top")
		(15 "B.Paste" user "Package Geometry/Pastemask Bottom")
		(5 "F.SilkS" user "Ref Des/Silkscreen Top")
		(7 "B.SilkS" user "Ref Des/Silkscreen Bottom")
		(1 "F.Mask" user "Board Geometry/Soldermask Top")
		(3 "B.Mask" user "Board Geometry/Soldermask Bottom")
		(17 "Dwgs.User" user "User.Drawings")
		(19 "Cmts.User" user "User.Comments")
		(21 "Eco1.User" user "User.Eco1")
		(23 "Eco2.User" user "User.Eco2")
		(25 "Edge.Cuts" user "Board Geometry/Outline")
		(27 "Margin" user)
		(31 "F.CrtYd" user "Package Geometry/Place Bound Top")
		(29 "B.CrtYd" user "Package Geometry/Place Bound Bottom")
		(35 "F.Fab" user "Ref Des/Assembly Top")
		(33 "B.Fab" user "Ref Des/Assembly Bottom")
	)
	(footprint ""
		(layer "F.Cu")
		(at 175.88738 -73.69556 180)
		(property "Reference" "R4D38"
			(at 0 0 180)
			(layer "F.SilkS")
			(hide yes)
			(effects
				(font
					(size 1.27 1.27)
				)
			)
		)
		(property "Value" ""
			(at 0 0 180)
			(layer "F.Fab")
			(effects
				(font
					(size 1.27 1.27)
				)
			)
		)
		(duplicate_pad_numbers_are_jumpers no)
		(fp_poly
			(pts
				(xy -0.2794 -0.1016) (xy 0.2794 -0.1016) (xy 0.2794 0.9906) (xy -0.2794 0.9906)
			)
			(stroke
				(width 0)
				(type default)
			)
			(fill no)
			(layer "F.CrtYd")
		)
		(fp_line
			(start 0.2794 0.9906)
			(end 0.2794 -0.1016)
			(stroke
				(width 0.1)
				(type default)
			)
			(layer "F.Fab")
		)
		(fp_line
			(start 0.2794 -0.1016)
			(end -0.2794 -0.1016)
			(stroke
				(width 0.1)
				(type default)
			)
			(layer "F.Fab")
		)
		(fp_line
			(start -0.2794 0.9906)
			(end 0.2794 0.9906)
			(stroke
				(width 0.1)
				(type default)
			)
			(layer "F.Fab")
		)
		(fp_line
			(start -0.2794 -0.1016)
			(end -0.2794 0.9906)
			(stroke
				(width 0.1)
				(type default)
			)
			(layer "F.Fab")
		)
		(pad "1" smd rect
			(at 0 0 180)
			(size 0.508 0.508)
			(layers "F.Cu" "F.Mask" "F.Paste")
			(net "P3V3_DB1200")
		)
		(pad "2" smd rect
			(at 0 0.889 180)
			(size 0.508 0.508)
			(layers "F.Cu" "F.Mask" "F.Paste")
			(net "FM_DB1200_SMB_SA1")
		)
		(zone
			(layer "F.Cu")
			(hatch none 0.5)
			(connect_pads
				(clearance 0)
			)
			(min_thickness 0.25)
			(keepout
				(tracks not_allowed)
				(vias allowed)
				(pads allowed)
				(copperpour not_allowed)
				(footprints allowed)
			)
			(placement
				(enabled no)
				(sheetname "")
			)
			(fill
				(thermal_gap 0.5)
				(thermal_bridge_width 0.5)
				(island_removal_mode 0)
			)
			(polygon
				(pts
					(xy 176.14138 -74.33056) (xy 175.63338 -74.33056) (xy 175.63338 -73.94956) (xy 176.14138 -73.94956)
				)
			)
		)
		(zone
			(layer "F.Cu")
			(hatch none 0.5)
			(connect_pads
				(clearance 0)
			)
			(min_thickness 0.25)
			(keepout
				(tracks allowed)
				(vias not_allowed)
				(pads allowed)
				(copperpour not_allowed)
				(footprints allowed)
			)
			(placement
				(enabled no)
				(sheetname "")
			)
			(fill
				(thermal_gap 0.5)
				(thermal_bridge_width 0.5)
				(island_removal_mode 0)
			)
			(polygon
				(pts
					(xy 176.14138 -73.94956) (xy 175.63338 -73.94956) (xy 175.63338 -74.33056) (xy 176.14138 -74.33056)
				)
			)
		)
	)
	(footprint ""
		(layer "F.Cu")
		(at 410.69006 -101.49332)
		(property "Reference" "R7W16"
			(at -0.8382 -0.67818 0)
			(unlocked yes)
			(layer "F.SilkS")
			(effects
				(font
					(size 0.4064 0.254)
					(thickness 0.1524)
				)
				(justify left)
			)
		)
		(property "Value" ""
			(at 0 0 0)
			(layer "F.Fab")
			(effects
				(font
					(size 1.27 1.27)
				)
			)
		)
		(duplicate_pad_numbers_are_jumpers no)
		(fp_poly
			(pts
				(xy -0.2794 -0.1016) (xy 0.2794 -0.1016) (xy 0.2794 0.9906) (xy -0.2794 0.9906)
			)
			(stroke
				(width 0)
				(type default)
			)
			(fill no)
			(layer "F.CrtYd")
		)
		(fp_line
			(start -0.2794 -0.1016)
			(end -0.2794 0.9906)
			(stroke
				(width 0.1)
				(type default)
			)
			(layer "F.Fab")
		)
		(fp_line
			(start -0.2794 0.9906)
			(end 0.2794 0.9906)
			(stroke
				(width 0.1)
				(type default)
			)
			(layer "F.Fab")
		)
		(fp_line
			(start 0.2794 -0.1016)
			(end -0.2794 -0.1016)
			(stroke
				(width 0.1)
				(type default)
			)
			(layer "F.Fab")
		)
		(fp_line
			(start 0.2794 0.9906)
			(end 0.2794 -0.1016)
			(stroke
				(width 0.1)
				(type default)
			)
			(layer "F.Fab")
		)
		(pad "1" smd rect
			(at 0 0)
			(size 0.508 0.508)
			(layers "F.Cu" "F.Mask" "F.Paste")
			(net "IRQ_DIMM_SAVE_LVT3_R_N")
		)
		(pad "2" smd rect
			(at 0 0.889)
			(size 0.508 0.508)
			(layers "F.Cu" "F.Mask" "F.Paste")
			(net "IRQ_DIMM_SAVE_LVT3_N")
		)
		(zone
			(layer "F.Cu")
			(hatch none 0.5)
			(connect_pads
				(clearance 0)
			)
			(min_thickness 0.25)
			(keepout
				(tracks allowed)
				(vias not_allowed)
				(pads allowed)
				(copperpour not_allowed)
				(footprints allowed)
			)
			(placement
				(enabled no)
				(sheetname "")
			)
			(fill
				(thermal_gap 0.5)
				(thermal_bridge_width 0.5)
				(island_removal_mode 0)
			)
			(polygon
				(pts
					(xy 410.43606 -101.23932) (xy 410.94406 -101.23932) (xy 410.94406 -100.85832) (xy 410.43606 -100.85832)
				)
			)
		)
		(zone
			(layer "F.Cu")
			(hatch none 0.5)
			(connect_pads
				(clearance 0)
			)
			(min_thickness 0.25)
			(keepout
				(tracks not_allowed)
				(vias allowed)
				(pads allowed)
				(copperpour not_allowed)
				(footprints allowed)
			)
			(placement
				(enabled no)
				(sheetname "")
			)
			(fill
				(thermal_gap 0.5)
				(thermal_bridge_width 0.5)
				(island_removal_mode 0)
			)
			(polygon
				(pts
					(xy 410.43606 -100.85832) (xy 410.94406 -100.85832) (xy 410.94406 -101.23932) (xy 410.43606 -101.23932)
				)
			)
		)
	)
	(footprint ""
		(layer "F.Cu")
		(at 362.276644 -10.916158)
		(property "Reference" "C7G5"
			(at 0 0 0)
			(layer "F.SilkS")
			(hide yes)
			(effects
				(font
					(size 1.27 1.27)
				)
			)
		)
		(property "Value" ""
			(at 0 0 0)
			(layer "F.Fab")
			(effects
				(font
					(size 1.27 1.27)
				)
			)
		)
		(duplicate_pad_numbers_are_jumpers no)
		(fp_rect
			(start -0.3048 0.9906)
			(end 0.3048 -0.1016)
			(stroke
				(width 0)
				(type default)
			)
			(fill no)
			(layer "F.CrtYd")
		)
		(fp_line
			(start -0.3048 -0.1016)
			(end -0.3048 0.9906)
			(stroke
				(width 0.1)
				(type default)
			)
			(layer "F.Fab")
		)
		(fp_line
			(start -0.3048 0.9906)
			(end 0.3048 0.9906)
			(stroke
				(width 0.1)
				(type default)
			)
			(layer "F.Fab")
		)
		(fp_line
			(start 0.3048 -0.1016)
			(end -0.3048 -0.1016)
			(stroke
				(width 0.1)
				(type default)
			)
			(layer "F.Fab")
		)
		(fp_line
			(start 0.3048 0.9906)
			(end 0.3048 -0.1016)
			(stroke
				(width 0.1)
				(type default)
			)
			(layer "F.Fab")
		)
		(pad "1" smd rect
			(at 0 0)
			(size 0.508 0.508)
			(layers "F.Cu" "F.Mask" "F.Paste")
			(net "P3E_CPU0_PE2_SS_TXP<15>")
		)
		(pad "2" smd rect
			(at 0 0.889)
			(size 0.508 0.508)
			(layers "F.Cu" "F.Mask" "F.Paste")
			(net "P3E_CPU0_PE2_SS_C_TXP<15>")
		)
		(zone
			(layer "F.Cu")
			(hatch none 0.5)
			(connect_pads
				(clearance 0)
			)
			(min_thickness 0.25)
			(keepout
				(tracks not_allowed)
				(vias allowed)
				(pads allowed)
				(copperpour not_allowed)
				(footprints allowed)
			)
			(placement
				(enabled no)
				(sheetname "")
			)
			(fill
				(thermal_gap 0.5)
				(thermal_bridge_width 0.5)
				(island_removal_mode 0)
			)
			(polygon
				(pts
					(xy 362.022644 -10.281158) (xy 362.530644 -10.281158) (xy 362.530644 -10.662158) (xy 362.022644 -10.662158)
				)
			)
		)
		(zone
			(layer "F.Cu")
			(hatch none 0.5)
			(connect_pads
				(clearance 0)
			)
			(min_thickness 0.25)
			(keepout
				(tracks allowed)
				(vias not_allowed)
				(pads allowed)
				(copperpour not_allowed)
				(footprints allowed)
			)
			(placement
				(enabled no)
				(sheetname "")
			)
			(fill
				(thermal_gap 0.5)
				(thermal_bridge_width 0.5)
				(island_removal_mode 0)
			)
			(polygon
				(pts
					(xy 362.022644 -10.281158) (xy 362.530644 -10.281158) (xy 362.530644 -10.662158) (xy 362.022644 -10.662158)
				)
			)
		)
	)
)
